# S9S_MB_2U (Grand Teton) — schematic netlist excerpt (pin names and nets, part order shuffled) for the footprints in the layout excerpt that follows; sources: Cadence DE-HDL packaged netlist, KiCad conversion of 03242023_DA0F0TMBIJ0_F0T_Motherboard_J_brd_V01_OCP.brd

C2379  Q_CAP  100NF 50V 10% EMPTY  pkg C0402  page 307 : A = UV_ADR_P2V5_COMP ; B = GND
R4042  Q_RES  33.2 1% CHIP  pkg 0402LF  page 225 : A = RST_CPU0_DRAM_AB_PLD_LVT3_R_N ; B = RST_CPU0_DRAM_AB_PLD_LVT3_N

(kicad_pcb
	(version 20260206)
	(generator "pcbnew")
	(generator_version "10.0")
	(general
		(thickness 1.6)
		(legacy_teardrops no)
	)
	(paper "A4")
	(title_block
		(title "03242023_DA0F0TMBIJ0_F0T_Motherboard_J_brd_V01_OCP.brd")
		(comment 1 "Grand Teton / footprints 1302-1303 of 6105")
	)
	(layers
		(0 "F.Cu" signal "TOP")
		(4 "In1.Cu" signal "GND")
		(6 "In2.Cu" signal "IN1")
		(8 "In3.Cu" signal "GND1")
		(10 "In4.Cu" signal "IN2")
		(12 "In5.Cu" signal "GND2")
		(14 "In6.Cu" signal "IN3")
		(16 "In7.Cu" signal "GND3")
		(18 "In8.Cu" signal "VCC")
		(20 "In9.Cu" signal "VCC1")
		(22 "In10.Cu" signal "GND4")
		(24 "In11.Cu" signal "IN4")
		(26 "In12.Cu" signal "GND5")
		(28 "In13.Cu" signal "IN5")
		(30 "In14.Cu" signal "GND6")
		(32 "In15.Cu" signal "IN6")
		(34 "In16.Cu" signal "GND7")
		(2 "B.Cu" signal "BOTTOM")
		(9 "F.Adhes" user "F.Adhesive")
		(11 "B.Adhes" user "B.Adhesive")
		(13 "F.Paste" user "Package Geometry/Pastemask Top")
		(15 "B.Paste" user "Package Geometry/Pastemask Bottom")
		(5 "F.SilkS" user "Ref Des/Silkscreen Top")
		(7 "B.SilkS" user "Ref Des/Silkscreen Bottom")
		(1 "F.Mask" user "Board Geometry/Soldermask Top")
		(3 "B.Mask" user "Board Geometry/Soldermask Bottom")
		(17 "Dwgs.User" user "User.Drawings")
		(19 "Cmts.User" user "User.Comments")
		(21 "Eco1.User" user "User.Eco1")
		(23 "Eco2.User" user "User.Eco2")
		(25 "Edge.Cuts" user "Board Geometry/Outline")
		(27 "Margin" user)
		(31 "F.CrtYd" user "Package Geometry/Place Bound Top")
		(29 "B.CrtYd" user "Package Geometry/Place Bound Bottom")
		(35 "F.Fab" user "Ref Des/Assembly Top")
		(33 "B.Fab" user "Ref Des/Assembly Bottom")
	)
	(footprint ""
		(layer "F.Cu")
		(at 112.78108 -106.238548 -90)
		(property "Reference" "R4042"
			(at 0 0 270)
			(layer "F.SilkS")
			(hide yes)
			(effects
				(font
					(size 1.27 1.27)
				)
			)
		)
		(property "Value" ""
			(at 0 0 270)
			(layer "F.Fab")
			(effects
				(font
					(size 1.27 1.27)
				)
			)
		)
		(duplicate_pad_numbers_are_jumpers no)
		(fp_line
			(start -0.7874 0.4064)
			(end -0.7874 -0.4064)
			(stroke
				(width 0.1524)
				(type default)
			)
			(layer "F.SilkS")
		)
		(fp_line
			(start 0.7874 0.4064)
			(end -0.7874 0.4064)
			(stroke
				(width 0.1524)
				(type default)
			)
			(layer "F.SilkS")
		)
		(fp_line
			(start -0.7874 -0.4064)
			(end 0.7874 -0.4064)
			(stroke
				(width 0.1524)
				(type default)
			)
			(layer "F.SilkS")
		)
		(fp_line
			(start 0.7874 -0.4064)
			(end 0.7874 0.4064)
			(stroke
				(width 0.1524)
				(type default)
			)
			(layer "F.SilkS")
		)
		(fp_line
			(start -0.67945 0.3048)
			(end -0.67945 -0.305054)
			(stroke
				(width 0.1)
				(type default)
			)
			(layer "F.Fab")
		)
		(fp_line
			(start -0.12065 0.3048)
			(end -0.67945 0.3048)
			(stroke
				(width 0.1)
				(type default)
			)
			(layer "F.Fab")
		)
		(fp_line
			(start 0.120396 0.3048)
			(end 0.120396 0.2794)
			(stroke
				(width 0.1)
				(type default)
			)
			(layer "F.Fab")
		)
		(fp_line
			(start 0.67945 0.3048)
			(end 0.120396 0.3048)
			(stroke
				(width 0.1)
				(type default)
			)
			(layer "F.Fab")
		)
		(fp_line
			(start -0.12065 0.2794)
			(end -0.12065 0.3048)
			(stroke
				(width 0.1)
				(type default)
			)
			(layer "F.Fab")
		)
		(fp_line
			(start 0.120396 0.2794)
			(end -0.12065 0.2794)
			(stroke
				(width 0.1)
				(type default)
			)
			(layer "F.Fab")
		)
		(fp_line
			(start -0.12065 -0.2794)
			(end 0.12065 -0.2794)
			(stroke
				(width 0.1)
				(type default)
			)
			(layer "F.Fab")
		)
		(fp_line
			(start 0.12065 -0.2794)
			(end 0.12065 -0.3048)
			(stroke
				(width 0.1)
				(type default)
			)
			(layer "F.Fab")
		)
		(fp_line
			(start 0.12065 -0.3048)
			(end 0.67945 -0.3048)
			(stroke
				(width 0.1)
				(type default)
			)
			(layer "F.Fab")
		)
		(fp_line
			(start 0.67945 -0.3048)
			(end 0.67945 0.3048)
			(stroke
				(width 0.1)
				(type default)
			)
			(layer "F.Fab")
		)
		(fp_line
			(start -0.67945 -0.305054)
			(end -0.12065 -0.305054)
			(stroke
				(width 0.1)
				(type default)
			)
			(layer "F.Fab")
		)
		(fp_line
			(start -0.12065 -0.305054)
			(end -0.12065 -0.2794)
			(stroke
				(width 0.1)
				(type default)
			)
			(layer "F.Fab")
		)
		(pad "1" smd circle
			(at -0.40005 0 270)
			(size 0 0)
			(layers "F.Cu" "F.Mask" "F.Paste")
			(net "RST_CPU0_DRAM_AB_PLD_LVT3_R_N")
		)
		(pad "2" smd circle
			(at 0.40005 0 270)
			(size 0 0)
			(layers "F.Cu" "F.Mask" "F.Paste")
			(net "RST_CPU0_DRAM_AB_PLD_LVT3_N")
		)
	)
	(footprint ""
		(layer "F.Cu")
		(at 201.8284 -92.6338 -90)
		(property "Reference" "C2379"
			(at 0 0 270)
			(layer "F.SilkS")
			(hide yes)
			(effects
				(font
					(size 1.27 1.27)
				)
			)
		)
		(property "Value" ""
			(at 0 0 270)
			(layer "F.Fab")
			(effects
				(font
					(size 1.27 1.27)
				)
			)
		)
		(duplicate_pad_numbers_are_jumpers no)
		(fp_line
			(start -0.7874 0.4064)
			(end -0.7874 -0.4064)
			(stroke
				(width 0.1524)
				(type default)
			)
			(layer "F.SilkS")
		)
		(fp_line
			(start 0.7874 0.4064)
			(end -0.7874 0.4064)
			(stroke
				(width 0.1524)
				(type default)
			)
			(layer "F.SilkS")
		)
		(fp_line
			(start -0.7874 -0.4064)
			(end 0.7874 -0.4064)
			(stroke
				(width 0.1524)
				(type default)
			)
			(layer "F.SilkS")
		)
		(fp_line
			(start 0.7874 -0.4064)
			(end 0.7874 0.4064)
			(stroke
				(width 0.1524)
				(type default)
			)
			(layer "F.SilkS")
		)
		(fp_line
			(start -0.67945 0.3048)
			(end -0.67945 -0.305054)
			(stroke
				(width 0.1)
				(type default)
			)
			(layer "F.Fab")
		)
		(fp_line
			(start -0.12065 0.3048)
			(end -0.67945 0.3048)
			(stroke
				(width 0.1)
				(type default)
			)
			(layer "F.Fab")
		)
		(fp_line
			(start 0.120396 0.3048)
			(end 0.120396 0.2794)
			(stroke
				(width 0.1)
				(type default)
			)
			(layer "F.Fab")
		)
		(fp_line
			(start 0.67945 0.3048)
			(end 0.120396 0.3048)
			(stroke
				(width 0.1)
				(type default)
			)
			(layer "F.Fab")
		)
		(fp_line
			(start -0.12065 0.2794)
			(end -0.12065 0.3048)
			(stroke
				(width 0.1)
				(type default)
			)
			(layer "F.Fab")
		)
		(fp_line
			(start 0.120396 0.2794)
			(end -0.12065 0.2794)
			(stroke
				(width 0.1)
				(type default)
			)
			(layer "F.Fab")
		)
		(fp_line
			(start -0.12065 -0.2794)
			(end 0.12065 -0.2794)
			(stroke
				(width 0.1)
				(type default)
			)
			(layer "F.Fab")
		)
		(fp_line
			(start 0.12065 -0.2794)
			(end 0.12065 -0.3048)
			(stroke
				(width 0.1)
				(type default)
			)
			(layer "F.Fab")
		)
		(fp_line
			(start 0.12065 -0.3048)
			(end 0.67945 -0.3048)
			(stroke
				(width 0.1)
				(type default)
			)
			(layer "F.Fab")
		)
		(fp_line
			(start 0.67945 -0.3048)
			(end 0.67945 0.3048)
			(stroke
				(width 0.1)
				(type default)
			)
			(layer "F.Fab")
		)
		(fp_line
			(start -0.67945 -0.305054)
			(end -0.12065 -0.305054)
			(stroke
				(width 0.1)
				(type default)
			)
			(layer "F.Fab")
		)
		(fp_line
			(start -0.12065 -0.305054)
			(end -0.12065 -0.2794)
			(stroke
				(width 0.1)
				(type default)
			)
			(layer "F.Fab")
		)
		(pad "1" smd circle
			(at -0.40005 0 270)
			(size 0 0)
			(layers "F.Cu" "F.Mask" "F.Paste")
			(net "UV_ADR_P2V5_COMP")
		)
		(pad "2" smd circle
			(at 0.40005 0 270)
			(size 0 0)
			(layers "F.Cu" "F.Mask" "F.Paste")
			(net "GND")
		)
	)
)
